(kicad_pcb
	(version 20260206)
	(generator "pcbnew")
	(generator_version "10.0")
	(general
		(thickness 1.6)
		(legacy_teardrops no)
	)
	(paper "A4")
	(title_block
		(title "12092022_DA0F0TFB6D0_F0T_FAN_BOARD_MP5048_D_brd_v02_OCP.brd")
		(comment 1 "Grand Teton / footprints 765-769 of 924")
	)
	(layers
		(0 "F.Cu" signal "TOP")
		(4 "In1.Cu" signal "GND")
		(6 "In2.Cu" signal "IN1")
		(8 "In3.Cu" signal "IN2")
		(10 "In4.Cu" signal "GND1")
		(2 "B.Cu" signal "BOTTOM")
		(9 "F.Adhes" user "F.Adhesive")
		(11 "B.Adhes" user "B.Adhesive")
		(13 "F.Paste" user "Package Geometry/Pastemask Top")
		(15 "B.Paste" user "Package Geometry/Pastemask Bottom")
		(5 "F.SilkS" user "Ref Des/Silkscreen Top")
		(7 "B.SilkS" user "Ref Des/Silkscreen Bottom")
		(1 "F.Mask" user "Board Geometry/Soldermask Top")
		(3 "B.Mask" user "Board Geometry/Soldermask Bottom")
		(17 "Dwgs.User" user "User.Drawings")
		(19 "Cmts.User" user "User.Comments")
		(21 "Eco1.User" user "User.Eco1")
		(23 "Eco2.User" user "User.Eco2")
		(25 "Edge.Cuts" user "Board Geometry/Outline")
		(27 "Margin" user)
		(31 "F.CrtYd" user "Package Geometry/Place Bound Top")
		(29 "B.CrtYd" user "Package Geometry/Place Bound Bottom")
		(35 "F.Fab" user "Ref Des/Assembly Top")
		(33 "B.Fab" user "Ref Des/Assembly Bottom")
	)
	(footprint ""
		(layer "B.Cu")
		(at 12.7 -258.572 90)
		(property "Reference" "PC56"
			(at 0 0 90)
			(layer "B.SilkS")
			(hide yes)
			(effects
				(font
					(size 1.27 1.27)
				)
				(justify mirror)
			)
		)
		(property "Value" ""
			(at 0 0 90)
			(layer "B.Fab")
			(effects
				(font
					(size 1.27 1.27)
				)
				(justify mirror)
			)
		)
		(duplicate_pad_numbers_are_jumpers no)
		(fp_line
			(start 0.7874 -0.4064)
			(end -0.7874 -0.4064)
			(stroke
				(width 0.1524)
				(type default)
			)
			(layer "B.SilkS")
		)
		(fp_line
			(start -0.7874 -0.4064)
			(end -0.7874 0.4064)
			(stroke
				(width 0.1524)
				(type default)
			)
			(layer "B.SilkS")
		)
		(fp_line
			(start 0.7874 0.4064)
			(end 0.7874 -0.4064)
			(stroke
				(width 0.1524)
				(type default)
			)
			(layer "B.SilkS")
		)
		(fp_line
			(start -0.7874 0.4064)
			(end 0.7874 0.4064)
			(stroke
				(width 0.1524)
				(type default)
			)
			(layer "B.SilkS")
		)
		(fp_line
			(start 0.67945 -0.305054)
			(end 0.12065 -0.305054)
			(stroke
				(width 0.1)
				(type default)
			)
			(layer "B.Fab")
		)
		(fp_line
			(start 0.12065 -0.305054)
			(end 0.12065 -0.2794)
			(stroke
				(width 0.1)
				(type default)
			)
			(layer "B.Fab")
		)
		(fp_line
			(start -0.12065 -0.3048)
			(end -0.67945 -0.3048)
			(stroke
				(width 0.1)
				(type default)
			)
			(layer "B.Fab")
		)
		(fp_line
			(start -0.67945 -0.3048)
			(end -0.67945 0.3048)
			(stroke
				(width 0.1)
				(type default)
			)
			(layer "B.Fab")
		)
		(fp_line
			(start 0.12065 -0.2794)
			(end -0.12065 -0.2794)
			(stroke
				(width 0.1)
				(type default)
			)
			(layer "B.Fab")
		)
		(fp_line
			(start -0.12065 -0.2794)
			(end -0.12065 -0.3048)
			(stroke
				(width 0.1)
				(type default)
			)
			(layer "B.Fab")
		)
		(fp_line
			(start 0.12065 0.2794)
			(end 0.12065 0.3048)
			(stroke
				(width 0.1)
				(type default)
			)
			(layer "B.Fab")
		)
		(fp_line
			(start -0.120396 0.2794)
			(end 0.12065 0.2794)
			(stroke
				(width 0.1)
				(type default)
			)
			(layer "B.Fab")
		)
		(fp_line
			(start 0.67945 0.3048)
			(end 0.67945 -0.305054)
			(stroke
				(width 0.1)
				(type default)
			)
			(layer "B.Fab")
		)
		(fp_line
			(start 0.12065 0.3048)
			(end 0.67945 0.3048)
			(stroke
				(width 0.1)
				(type default)
			)
			(layer "B.Fab")
		)
		(fp_line
			(start -0.120396 0.3048)
			(end -0.120396 0.2794)
			(stroke
				(width 0.1)
				(type default)
			)
			(layer "B.Fab")
		)
		(fp_line
			(start -0.67945 0.3048)
			(end -0.120396 0.3048)
			(stroke
				(width 0.1)
				(type default)
			)
			(layer "B.Fab")
		)
		(pad "1" smd circle
			(at 0.40005 0 270)
			(size 0 0)
			(layers "B.Cu" "B.Mask" "B.Paste")
			(net "FAN_7_P3V_R")
		)
		(pad "2" smd circle
			(at -0.40005 0 270)
			(size 0 0)
			(layers "B.Cu" "B.Mask" "B.Paste")
			(net "GND")
		)
	)
	(footprint ""
		(layer "B.Cu")
		(at 4.826 -64.837056 -90)
		(property "Reference" "PC41"
			(at 0 0 90)
			(layer "B.SilkS")
			(hide yes)
			(effects
				(font
					(size 1.27 1.27)
				)
				(justify mirror)
			)
		)
		(property "Value" ""
			(at 0 0 90)
			(layer "B.Fab")
			(effects
				(font
					(size 1.27 1.27)
				)
				(justify mirror)
			)
		)
		(duplicate_pad_numbers_are_jumpers no)
		(fp_line
			(start -0.7874 0.4064)
			(end 0.7874 0.4064)
			(stroke
				(width 0.1524)
				(type default)
			)
			(layer "B.SilkS")
		)
		(fp_line
			(start 0.7874 0.4064)
			(end 0.7874 -0.4064)
			(stroke
				(width 0.1524)
				(type default)
			)
			(layer "B.SilkS")
		)
		(fp_line
			(start -0.7874 -0.4064)
			(end -0.7874 0.4064)
			(stroke
				(width 0.1524)
				(type default)
			)
			(layer "B.SilkS")
		)
		(fp_line
			(start 0.7874 -0.4064)
			(end -0.7874 -0.4064)
			(stroke
				(width 0.1524)
				(type default)
			)
			(layer "B.SilkS")
		)
		(fp_line
			(start -0.67945 0.3048)
			(end -0.120396 0.3048)
			(stroke
				(width 0.1)
				(type default)
			)
			(layer "B.Fab")
		)
		(fp_line
			(start -0.120396 0.3048)
			(end -0.120396 0.2794)
			(stroke
				(width 0.1)
				(type default)
			)
			(layer "B.Fab")
		)
		(fp_line
			(start 0.12065 0.3048)
			(end 0.67945 0.3048)
			(stroke
				(width 0.1)
				(type default)
			)
			(layer "B.Fab")
		)
		(fp_line
			(start 0.67945 0.3048)
			(end 0.67945 -0.305054)
			(stroke
				(width 0.1)
				(type default)
			)
			(layer "B.Fab")
		)
		(fp_line
			(start -0.120396 0.2794)
			(end 0.12065 0.2794)
			(stroke
				(width 0.1)
				(type default)
			)
			(layer "B.Fab")
		)
		(fp_line
			(start 0.12065 0.2794)
			(end 0.12065 0.3048)
			(stroke
				(width 0.1)
				(type default)
			)
			(layer "B.Fab")
		)
		(fp_line
			(start -0.12065 -0.2794)
			(end -0.12065 -0.3048)
			(stroke
				(width 0.1)
				(type default)
			)
			(layer "B.Fab")
		)
		(fp_line
			(start 0.12065 -0.2794)
			(end -0.12065 -0.2794)
			(stroke
				(width 0.1)
				(type default)
			)
			(layer "B.Fab")
		)
		(fp_line
			(start -0.67945 -0.3048)
			(end -0.67945 0.3048)
			(stroke
				(width 0.1)
				(type default)
			)
			(layer "B.Fab")
		)
		(fp_line
			(start -0.12065 -0.3048)
			(end -0.67945 -0.3048)
			(stroke
				(width 0.1)
				(type default)
			)
			(layer "B.Fab")
		)
		(fp_line
			(start 0.12065 -0.305054)
			(end 0.12065 -0.2794)
			(stroke
				(width 0.1)
				(type default)
			)
			(layer "B.Fab")
		)
		(fp_line
			(start 0.67945 -0.305054)
			(end 0.12065 -0.305054)
			(stroke
				(width 0.1)
				(type default)
			)
			(layer "B.Fab")
		)
		(pad "1" smd circle
			(at 0.40005 0 90)
			(size 0 0)
			(layers "B.Cu" "B.Mask" "B.Paste")
			(net "FAN_4_TIMER")
		)
		(pad "2" smd circle
			(at -0.40005 0 90)
			(size 0 0)
			(layers "B.Cu" "B.Mask" "B.Paste")
			(net "GND")
		)
	)
	(footprint ""
		(layer "B.Cu")
		(at 7.947914 -252.095 180)
		(property "Reference" "U383"
			(at -0.434086 1.75133 0)
			(unlocked yes)
			(layer "B.SilkS")
			(effects
				(font
					(size 0.7874 0.5842)
					(thickness 0.1524)
				)
				(justify mirror)
			)
		)
		(property "Value" ""
			(at 0 0 0)
			(layer "B.Fab")
			(effects
				(font
					(size 1.27 1.27)
				)
				(justify mirror)
			)
		)
		(duplicate_pad_numbers_are_jumpers no)
		(fp_line
			(start 1.7018 1.1176)
			(end 1.7018 -1.1176)
			(stroke
				(width 0.1524)
				(type default)
			)
			(layer "B.SilkS")
		)
		(fp_line
			(start 0.254 -1.1176)
			(end 1.7018 -1.1176)
			(stroke
				(width 0.1524)
				(type default)
			)
			(layer "B.SilkS")
		)
		(fp_line
			(start 0 -0.7112)
			(end 0.254 -1.1176)
			(stroke
				(width 0.1524)
				(type default)
			)
			(layer "B.SilkS")
		)
		(fp_line
			(start -0.254 -1.1176)
			(end 0 -0.7112)
			(stroke
				(width 0.1524)
				(type default)
			)
			(layer "B.SilkS")
		)
		(fp_line
			(start -1.7018 1.1176)
			(end 1.7018 1.1176)
			(stroke
				(width 0.1524)
				(type default)
			)
			(layer "B.SilkS")
		)
		(fp_line
			(start -1.7018 -1.1176)
			(end -0.254 -1.1176)
			(stroke
				(width 0.1524)
				(type default)
			)
			(layer "B.SilkS")
		)
		(fp_line
			(start -1.7018 -1.1176)
			(end -1.7018 1.1176)
			(stroke
				(width 0.1524)
				(type default)
			)
			(layer "B.SilkS")
		)
		(fp_poly
			(pts
				(xy 1.8161 -0.675386) (xy 2.4003 -0.446786) (xy 2.4003 -0.878586)
			)
			(stroke
				(width 0)
				(type default)
			)
			(fill yes)
			(layer "B.SilkS")
		)
		(fp_line
			(start 1.5494 1.1176)
			(end 1.5494 -1.1176)
			(stroke
				(width 0.1)
				(type default)
			)
			(layer "B.Fab")
		)
		(fp_line
			(start 0.254 -1.1176)
			(end 1.5494 -1.1176)
			(stroke
				(width 0.1)
				(type default)
			)
			(layer "B.Fab")
		)
		(fp_line
			(start -0.254 -1.1176)
			(end 0.254 -1.1176)
			(stroke
				(width 0.1)
				(type default)
			)
			(layer "B.Fab")
		)
		(fp_line
			(start -1.5494 1.1176)
			(end 1.5494 1.1176)
			(stroke
				(width 0.1)
				(type default)
			)
			(layer "B.Fab")
		)
		(fp_line
			(start -1.5494 -1.1176)
			(end -0.254 -1.1176)
			(stroke
				(width 0.1)
				(type default)
			)
			(layer "B.Fab")
		)
		(fp_line
			(start -1.5494 -1.1176)
			(end -1.5494 1.1176)
			(stroke
				(width 0.1)
				(type default)
			)
			(layer "B.Fab")
		)
		(fp_poly
			(pts
				(xy 1.8161 -0.675386) (xy 2.4003 -0.446786) (xy 2.4003 -0.878586)
			)
			(stroke
				(width 0)
				(type default)
			)
			(fill yes)
			(layer "B.Fab")
		)
		(pad "1" smd rect
			(at 0.962406 -0.649986 90)
			(size 0.3302 1.1684)
			(layers "B.Cu" "B.Mask" "B.Paste")
			(net "FAN_6_PRESENT_R")
		)
		(pad "2" smd rect
			(at 0.962406 0 90)
			(size 0.3302 1.1684)
			(layers "B.Cu" "B.Mask" "B.Paste")
			(net "P52V_FAN_6_BUFF_EN_R")
		)
		(pad "3" smd rect
			(at 0.962406 0.649986 90)
			(size 0.3302 1.1684)
			(layers "B.Cu" "B.Mask" "B.Paste")
			(net "GND")
		)
		(pad "4" smd rect
			(at -0.962406 0.649986 90)
			(size 0.3302 1.1684)
			(layers "B.Cu" "B.Mask" "B.Paste")
			(net "P52V_FAN_6_EN")
		)
		(pad "5" smd rect
			(at -0.962406 -0.649986 90)
			(size 0.3302 1.1684)
			(layers "B.Cu" "B.Mask" "B.Paste")
			(net "P3V3_AUX")
		)
	)
	(footprint ""
		(layer "B.Cu")
		(at 33.4518 -276.3774)
		(property "Reference" "C2098"
			(at 0 0 0)
			(layer "B.SilkS")
			(hide yes)
			(effects
				(font
					(size 1.27 1.27)
				)
				(justify mirror)
			)
		)
		(property "Value" ""
			(at 0 0 0)
			(layer "B.Fab")
			(effects
				(font
					(size 1.27 1.27)
				)
				(justify mirror)
			)
		)
		(duplicate_pad_numbers_are_jumpers no)
		(fp_line
			(start -2.2098 -0.9398)
			(end -2.2098 0.9398)
			(stroke
				(width 0.1524)
				(type default)
			)
			(layer "B.SilkS")
		)
		(fp_line
			(start -2.2098 0.9398)
			(end 2.2098 0.9398)
			(stroke
				(width 0.1524)
				(type default)
			)
			(layer "B.SilkS")
		)
		(fp_line
			(start 2.2098 -0.9398)
			(end -2.2098 -0.9398)
			(stroke
				(width 0.1524)
				(type default)
			)
			(layer "B.SilkS")
		)
		(fp_line
			(start 2.2098 0.9398)
			(end 2.2098 -0.9398)
			(stroke
				(width 0.1524)
				(type default)
			)
			(layer "B.SilkS")
		)
		(fp_line
			(start -1.700022 -0.899922)
			(end -1.700022 0.899922)
			(stroke
				(width 0.1)
				(type default)
			)
			(layer "B.Fab")
		)
		(fp_line
			(start -1.700022 0.899922)
			(end 1.700022 0.899922)
			(stroke
				(width 0.1)
				(type default)
			)
			(layer "B.Fab")
		)
		(fp_line
			(start 1.700022 -0.899922)
			(end -1.700022 -0.899922)
			(stroke
				(width 0.1)
				(type default)
			)
			(layer "B.Fab")
		)
		(fp_line
			(start 1.700022 0.899922)
			(end 1.700022 -0.899922)
			(stroke
				(width 0.1)
				(type default)
			)
			(layer "B.Fab")
		)
		(pad "1" smd rect
			(at 1.4732 0)
			(size 1.1684 1.5748)
			(layers "B.Cu" "B.Mask" "B.Paste")
			(net "P52V_FAN_0")
		)
		(pad "2" smd rect
			(at -1.4732 0)
			(size 1.1684 1.5748)
			(layers "B.Cu" "B.Mask" "B.Paste")
			(net "GND")
		)
	)
	(footprint ""
		(layer "B.Cu")
		(at 44.069 -234.315 180)
		(property "Reference" "C2100"
			(at 0 0 0)
			(layer "B.SilkS")
			(hide yes)
			(effects
				(font
					(size 1.27 1.27)
				)
				(justify mirror)
			)
		)
		(property "Value" ""
			(at 0 0 0)
			(layer "B.Fab")
			(effects
				(font
					(size 1.27 1.27)
				)
				(justify mirror)
			)
		)
		(duplicate_pad_numbers_are_jumpers no)
		(fp_line
			(start 2.2098 0.9398)
			(end 2.2098 -0.9398)
			(stroke
				(width 0.1524)
				(type default)
			)
			(layer "B.SilkS")
		)
		(fp_line
			(start 2.2098 -0.9398)
			(end -2.2098 -0.9398)
			(stroke
				(width 0.1524)
				(type default)
			)
			(layer "B.SilkS")
		)
		(fp_line
			(start -2.2098 0.9398)
			(end 2.2098 0.9398)
			(stroke
				(width 0.1524)
				(type default)
			)
			(layer "B.SilkS")
		)
		(fp_line
			(start -2.2098 -0.9398)
			(end -2.2098 0.9398)
			(stroke
				(width 0.1524)
				(type default)
			)
			(layer "B.SilkS")
		)
		(fp_line
			(start 1.700022 0.899922)
			(end 1.700022 -0.899922)
			(stroke
				(width 0.1)
				(type default)
			)
			(layer "B.Fab")
		)
		(fp_line
			(start 1.700022 -0.899922)
			(end -1.700022 -0.899922)
			(stroke
				(width 0.1)
				(type default)
			)
			(layer "B.Fab")
		)
		(fp_line
			(start -1.700022 0.899922)
			(end 1.700022 0.899922)
			(stroke
				(width 0.1)
				(type default)
			)
			(layer "B.Fab")
		)
		(fp_line
			(start -1.700022 -0.899922)
			(end -1.700022 0.899922)
			(stroke
				(width 0.1)
				(type default)
			)
			(layer "B.Fab")
		)
		(pad "1" smd rect
			(at 1.4732 0 180)
			(size 1.1684 1.5748)
			(layers "B.Cu" "B.Mask" "B.Paste")
			(net "P52V_FAN_1")
		)
		(pad "2" smd rect
			(at -1.4732 0 180)
			(size 1.1684 1.5748)
			(layers "B.Cu" "B.Mask" "B.Paste")
			(net "GND")
		)
	)
)
